(kicad_pcb
	(version 20260206)
	(generator "pcbnew")
	(generator_version "10.0")
	(general
		(thickness 1.6)
		(legacy_teardrops no)
	)
	(paper "A4")
	(title_block
		(title "04192023_DAF0TMB3IC0_F0TG_MB_C_brd_V02_OCP.brd")
		(comment 1 "Grand Teton / footprints 7901-7907 of 8354")
	)
	(layers
		(0 "F.Cu" signal "TOP")
		(4 "In1.Cu" signal "GND")
		(6 "In2.Cu" signal "IN1")
		(8 "In3.Cu" signal "GND1")
		(10 "In4.Cu" signal "IN2")
		(12 "In5.Cu" signal "GND2")
		(14 "In6.Cu" signal "IN3")
		(16 "In7.Cu" signal "GND3")
		(18 "In8.Cu" signal "VCC")
		(20 "In9.Cu" signal "VCC1")
		(22 "In10.Cu" signal "GND4")
		(24 "In11.Cu" signal "IN4")
		(26 "In12.Cu" signal "GND5")
		(28 "In13.Cu" signal "IN5")
		(30 "In14.Cu" signal "GND6")
		(32 "In15.Cu" signal "IN6")
		(34 "In16.Cu" signal "GND7")
		(2 "B.Cu" signal "BOTTOM")
		(9 "F.Adhes" user "F.Adhesive")
		(11 "B.Adhes" user "B.Adhesive")
		(13 "F.Paste" user "Package Geometry/Pastemask Top")
		(15 "B.Paste" user "Package Geometry/Pastemask Bottom")
		(5 "F.SilkS" user "Ref Des/Silkscreen Top")
		(7 "B.SilkS" user "Ref Des/Silkscreen Bottom")
		(1 "F.Mask" user "Board Geometry/Soldermask Top")
		(3 "B.Mask" user "Board Geometry/Soldermask Bottom")
		(17 "Dwgs.User" user "User.Drawings")
		(19 "Cmts.User" user "User.Comments")
		(21 "Eco1.User" user "User.Eco1")
		(23 "Eco2.User" user "User.Eco2")
		(25 "Edge.Cuts" user "Board Geometry/Outline")
		(27 "Margin" user)
		(31 "F.CrtYd" user "Package Geometry/Place Bound Top")
		(29 "B.CrtYd" user "Package Geometry/Place Bound Bottom")
		(35 "F.Fab" user "Ref Des/Assembly Top")
		(33 "B.Fab" user "Ref Des/Assembly Bottom")
	)
	(footprint ""
		(layer "B.Cu")
		(at 370.905278 -146.552158)
		(property "Reference" "C298"
			(at 0 0 0)
			(layer "B.SilkS")
			(hide yes)
			(effects
				(font
					(size 1.27 1.27)
				)
				(justify mirror)
			)
		)
		(property "Value" ""
			(at 0 0 0)
			(layer "B.Fab")
			(effects
				(font
					(size 1.27 1.27)
				)
				(justify mirror)
			)
		)
		(duplicate_pad_numbers_are_jumpers no)
		(fp_line
			(start -0.7874 -0.4064)
			(end -0.7874 0.4064)
			(stroke
				(width 0.1524)
				(type default)
			)
			(layer "B.SilkS")
		)
		(fp_line
			(start -0.7874 0.4064)
			(end 0.7874 0.4064)
			(stroke
				(width 0.1524)
				(type default)
			)
			(layer "B.SilkS")
		)
		(fp_line
			(start 0.7874 -0.4064)
			(end -0.7874 -0.4064)
			(stroke
				(width 0.1524)
				(type default)
			)
			(layer "B.SilkS")
		)
		(fp_line
			(start 0.7874 0.4064)
			(end 0.7874 -0.4064)
			(stroke
				(width 0.1524)
				(type default)
			)
			(layer "B.SilkS")
		)
		(fp_line
			(start -0.67945 -0.3048)
			(end -0.67945 0.3048)
			(stroke
				(width 0.1)
				(type default)
			)
			(layer "B.Fab")
		)
		(fp_line
			(start -0.67945 0.3048)
			(end -0.120396 0.3048)
			(stroke
				(width 0.1)
				(type default)
			)
			(layer "B.Fab")
		)
		(fp_line
			(start -0.12065 -0.3048)
			(end -0.67945 -0.3048)
			(stroke
				(width 0.1)
				(type default)
			)
			(layer "B.Fab")
		)
		(fp_line
			(start -0.12065 -0.2794)
			(end -0.12065 -0.3048)
			(stroke
				(width 0.1)
				(type default)
			)
			(layer "B.Fab")
		)
		(fp_line
			(start -0.120396 0.2794)
			(end 0.12065 0.2794)
			(stroke
				(width 0.1)
				(type default)
			)
			(layer "B.Fab")
		)
		(fp_line
			(start -0.120396 0.3048)
			(end -0.120396 0.2794)
			(stroke
				(width 0.1)
				(type default)
			)
			(layer "B.Fab")
		)
		(fp_line
			(start 0.12065 -0.305054)
			(end 0.12065 -0.2794)
			(stroke
				(width 0.1)
				(type default)
			)
			(layer "B.Fab")
		)
		(fp_line
			(start 0.12065 -0.2794)
			(end -0.12065 -0.2794)
			(stroke
				(width 0.1)
				(type default)
			)
			(layer "B.Fab")
		)
		(fp_line
			(start 0.12065 0.2794)
			(end 0.12065 0.3048)
			(stroke
				(width 0.1)
				(type default)
			)
			(layer "B.Fab")
		)
		(fp_line
			(start 0.12065 0.3048)
			(end 0.67945 0.3048)
			(stroke
				(width 0.1)
				(type default)
			)
			(layer "B.Fab")
		)
		(fp_line
			(start 0.67945 -0.305054)
			(end 0.12065 -0.305054)
			(stroke
				(width 0.1)
				(type default)
			)
			(layer "B.Fab")
		)
		(fp_line
			(start 0.67945 0.3048)
			(end 0.67945 -0.305054)
			(stroke
				(width 0.1)
				(type default)
			)
			(layer "B.Fab")
		)
		(pad "1" smd circle
			(at 0.40005 0 180)
			(size 0 0)
			(layers "B.Cu" "B.Mask" "B.Paste")
			(net "SVID_PVDDCR_CPU0_P0_SVTO")
		)
		(pad "2" smd circle
			(at -0.40005 0 180)
			(size 0 0)
			(layers "B.Cu" "B.Mask" "B.Paste")
			(net "GND")
		)
	)
	(footprint ""
		(layer "B.Cu")
		(at 328.92365 -34.139886 180)
		(property "Reference" "C35"
			(at 0 0 0)
			(layer "B.SilkS")
			(hide yes)
			(effects
				(font
					(size 1.27 1.27)
				)
				(justify mirror)
			)
		)
		(property "Value" ""
			(at 0 0 0)
			(layer "B.Fab")
			(effects
				(font
					(size 1.27 1.27)
				)
				(justify mirror)
			)
		)
		(duplicate_pad_numbers_are_jumpers no)
		(fp_line
			(start 0.7874 0.4064)
			(end 0.7874 -0.4064)
			(stroke
				(width 0.1524)
				(type default)
			)
			(layer "B.SilkS")
		)
		(fp_line
			(start 0.7874 -0.4064)
			(end -0.7874 -0.4064)
			(stroke
				(width 0.1524)
				(type default)
			)
			(layer "B.SilkS")
		)
		(fp_line
			(start -0.7874 0.4064)
			(end 0.7874 0.4064)
			(stroke
				(width 0.1524)
				(type default)
			)
			(layer "B.SilkS")
		)
		(fp_line
			(start -0.7874 -0.4064)
			(end -0.7874 0.4064)
			(stroke
				(width 0.1524)
				(type default)
			)
			(layer "B.SilkS")
		)
		(fp_line
			(start 0.67945 0.3048)
			(end 0.67945 -0.305054)
			(stroke
				(width 0.1)
				(type default)
			)
			(layer "B.Fab")
		)
		(fp_line
			(start 0.67945 -0.305054)
			(end 0.12065 -0.305054)
			(stroke
				(width 0.1)
				(type default)
			)
			(layer "B.Fab")
		)
		(fp_line
			(start 0.12065 0.3048)
			(end 0.67945 0.3048)
			(stroke
				(width 0.1)
				(type default)
			)
			(layer "B.Fab")
		)
		(fp_line
			(start 0.12065 0.2794)
			(end 0.12065 0.3048)
			(stroke
				(width 0.1)
				(type default)
			)
			(layer "B.Fab")
		)
		(fp_line
			(start 0.12065 -0.2794)
			(end -0.12065 -0.2794)
			(stroke
				(width 0.1)
				(type default)
			)
			(layer "B.Fab")
		)
		(fp_line
			(start 0.12065 -0.305054)
			(end 0.12065 -0.2794)
			(stroke
				(width 0.1)
				(type default)
			)
			(layer "B.Fab")
		)
		(fp_line
			(start -0.120396 0.3048)
			(end -0.120396 0.2794)
			(stroke
				(width 0.1)
				(type default)
			)
			(layer "B.Fab")
		)
		(fp_line
			(start -0.120396 0.2794)
			(end 0.12065 0.2794)
			(stroke
				(width 0.1)
				(type default)
			)
			(layer "B.Fab")
		)
		(fp_line
			(start -0.12065 -0.2794)
			(end -0.12065 -0.3048)
			(stroke
				(width 0.1)
				(type default)
			)
			(layer "B.Fab")
		)
		(fp_line
			(start -0.12065 -0.3048)
			(end -0.67945 -0.3048)
			(stroke
				(width 0.1)
				(type default)
			)
			(layer "B.Fab")
		)
		(fp_line
			(start -0.67945 0.3048)
			(end -0.120396 0.3048)
			(stroke
				(width 0.1)
				(type default)
			)
			(layer "B.Fab")
		)
		(fp_line
			(start -0.67945 -0.3048)
			(end -0.67945 0.3048)
			(stroke
				(width 0.1)
				(type default)
			)
			(layer "B.Fab")
		)
		(pad "1" smd circle
			(at 0.40005 0)
			(size 0 0)
			(layers "B.Cu" "B.Mask" "B.Paste")
			(net "P12V_E1S_0_ISENSE_MAM")
		)
		(pad "2" smd circle
			(at -0.40005 0)
			(size 0 0)
			(layers "B.Cu" "B.Mask" "B.Paste")
			(net "GND")
		)
	)
	(footprint ""
		(layer "B.Cu")
		(at 371.900958 -271.853152 90)
		(property "Reference" "C2249"
			(at 0 0 90)
			(layer "B.SilkS")
			(hide yes)
			(effects
				(font
					(size 1.27 1.27)
				)
				(justify mirror)
			)
		)
		(property "Value" ""
			(at 0 0 90)
			(layer "B.Fab")
			(effects
				(font
					(size 1.27 1.27)
				)
				(justify mirror)
			)
		)
		(duplicate_pad_numbers_are_jumpers no)
		(fp_line
			(start 0.7874 -0.4064)
			(end -0.7874 -0.4064)
			(stroke
				(width 0.1524)
				(type default)
			)
			(layer "B.SilkS")
		)
		(fp_line
			(start -0.7874 -0.4064)
			(end -0.7874 0.4064)
			(stroke
				(width 0.1524)
				(type default)
			)
			(layer "B.SilkS")
		)
		(fp_line
			(start 0.7874 0.4064)
			(end 0.7874 -0.4064)
			(stroke
				(width 0.1524)
				(type default)
			)
			(layer "B.SilkS")
		)
		(fp_line
			(start -0.7874 0.4064)
			(end 0.7874 0.4064)
			(stroke
				(width 0.1524)
				(type default)
			)
			(layer "B.SilkS")
		)
		(fp_line
			(start 0.67945 -0.305054)
			(end 0.12065 -0.305054)
			(stroke
				(width 0.1)
				(type default)
			)
			(layer "B.Fab")
		)
		(fp_line
			(start 0.12065 -0.305054)
			(end 0.12065 -0.2794)
			(stroke
				(width 0.1)
				(type default)
			)
			(layer "B.Fab")
		)
		(fp_line
			(start -0.12065 -0.3048)
			(end -0.67945 -0.3048)
			(stroke
				(width 0.1)
				(type default)
			)
			(layer "B.Fab")
		)
		(fp_line
			(start -0.67945 -0.3048)
			(end -0.67945 0.3048)
			(stroke
				(width 0.1)
				(type default)
			)
			(layer "B.Fab")
		)
		(fp_line
			(start 0.12065 -0.2794)
			(end -0.12065 -0.2794)
			(stroke
				(width 0.1)
				(type default)
			)
			(layer "B.Fab")
		)
		(fp_line
			(start -0.12065 -0.2794)
			(end -0.12065 -0.3048)
			(stroke
				(width 0.1)
				(type default)
			)
			(layer "B.Fab")
		)
		(fp_line
			(start 0.12065 0.2794)
			(end 0.12065 0.3048)
			(stroke
				(width 0.1)
				(type default)
			)
			(layer "B.Fab")
		)
		(fp_line
			(start -0.120396 0.2794)
			(end 0.12065 0.2794)
			(stroke
				(width 0.1)
				(type default)
			)
			(layer "B.Fab")
		)
		(fp_line
			(start 0.67945 0.3048)
			(end 0.67945 -0.305054)
			(stroke
				(width 0.1)
				(type default)
			)
			(layer "B.Fab")
		)
		(fp_line
			(start 0.12065 0.3048)
			(end 0.67945 0.3048)
			(stroke
				(width 0.1)
				(type default)
			)
			(layer "B.Fab")
		)
		(fp_line
			(start -0.120396 0.3048)
			(end -0.120396 0.2794)
			(stroke
				(width 0.1)
				(type default)
			)
			(layer "B.Fab")
		)
		(fp_line
			(start -0.67945 0.3048)
			(end -0.120396 0.3048)
			(stroke
				(width 0.1)
				(type default)
			)
			(layer "B.Fab")
		)
		(pad "1" smd circle
			(at 0.40005 0 270)
			(size 0 0)
			(layers "B.Cu" "B.Mask" "B.Paste")
			(net "PVDDCR_CPU1_P0")
		)
		(pad "2" smd circle
			(at -0.40005 0 270)
			(size 0 0)
			(layers "B.Cu" "B.Mask" "B.Paste")
			(net "GND")
		)
	)
	(footprint ""
		(layer "B.Cu")
		(at 88.306402 -386.766562 90)
		(property "Reference" "C288"
			(at 0 0 90)
			(layer "B.SilkS")
			(hide yes)
			(effects
				(font
					(size 1.27 1.27)
				)
				(justify mirror)
			)
		)
		(property "Value" ""
			(at 0 0 90)
			(layer "B.Fab")
			(effects
				(font
					(size 1.27 1.27)
				)
				(justify mirror)
			)
		)
		(duplicate_pad_numbers_are_jumpers no)
		(fp_line
			(start 0.299974 -0.150114)
			(end -0.299974 -0.150114)
			(stroke
				(width 0.1)
				(type default)
			)
			(layer "B.Fab")
		)
		(fp_line
			(start -0.299974 -0.150114)
			(end -0.299974 0.150114)
			(stroke
				(width 0.1)
				(type default)
			)
			(layer "B.Fab")
		)
		(fp_line
			(start 0.299974 0.150114)
			(end 0.299974 -0.150114)
			(stroke
				(width 0.1)
				(type default)
			)
			(layer "B.Fab")
		)
		(fp_line
			(start -0.299974 0.150114)
			(end 0.299974 0.150114)
			(stroke
				(width 0.1)
				(type default)
			)
			(layer "B.Fab")
		)
		(pad "1" smd rect
			(at 0.2667 0 270)
			(size 0.3048 0.381)
			(layers "B.Cu" "B.Mask" "B.Paste")
			(net "P1V8_CPU1_RT1_1A")
		)
		(pad "2" smd rect
			(at -0.2667 0 270)
			(size 0.3048 0.381)
			(layers "B.Cu" "B.Mask" "B.Paste")
			(net "GND")
		)
	)
	(footprint ""
		(layer "B.Cu")
		(at 402.539962 -314.925964 180)
		(property "Reference" "C216"
			(at 0 0 0)
			(layer "B.SilkS")
			(hide yes)
			(effects
				(font
					(size 1.27 1.27)
				)
				(justify mirror)
			)
		)
		(property "Value" ""
			(at 0 0 0)
			(layer "B.Fab")
			(effects
				(font
					(size 1.27 1.27)
				)
				(justify mirror)
			)
		)
		(duplicate_pad_numbers_are_jumpers no)
		(fp_line
			(start 0.7874 0.4064)
			(end 0.7874 -0.4064)
			(stroke
				(width 0.1524)
				(type default)
			)
			(layer "B.SilkS")
		)
		(fp_line
			(start 0.7874 -0.4064)
			(end -0.7874 -0.4064)
			(stroke
				(width 0.1524)
				(type default)
			)
			(layer "B.SilkS")
		)
		(fp_line
			(start -0.7874 0.4064)
			(end 0.7874 0.4064)
			(stroke
				(width 0.1524)
				(type default)
			)
			(layer "B.SilkS")
		)
		(fp_line
			(start -0.7874 -0.4064)
			(end -0.7874 0.4064)
			(stroke
				(width 0.1524)
				(type default)
			)
			(layer "B.SilkS")
		)
		(fp_line
			(start 0.67945 0.3048)
			(end 0.67945 -0.305054)
			(stroke
				(width 0.1)
				(type default)
			)
			(layer "B.Fab")
		)
		(fp_line
			(start 0.67945 -0.305054)
			(end 0.12065 -0.305054)
			(stroke
				(width 0.1)
				(type default)
			)
			(layer "B.Fab")
		)
		(fp_line
			(start 0.12065 0.3048)
			(end 0.67945 0.3048)
			(stroke
				(width 0.1)
				(type default)
			)
			(layer "B.Fab")
		)
		(fp_line
			(start 0.12065 0.2794)
			(end 0.12065 0.3048)
			(stroke
				(width 0.1)
				(type default)
			)
			(layer "B.Fab")
		)
		(fp_line
			(start 0.12065 -0.2794)
			(end -0.12065 -0.2794)
			(stroke
				(width 0.1)
				(type default)
			)
			(layer "B.Fab")
		)
		(fp_line
			(start 0.12065 -0.305054)
			(end 0.12065 -0.2794)
			(stroke
				(width 0.1)
				(type default)
			)
			(layer "B.Fab")
		)
		(fp_line
			(start -0.120396 0.3048)
			(end -0.120396 0.2794)
			(stroke
				(width 0.1)
				(type default)
			)
			(layer "B.Fab")
		)
		(fp_line
			(start -0.120396 0.2794)
			(end 0.12065 0.2794)
			(stroke
				(width 0.1)
				(type default)
			)
			(layer "B.Fab")
		)
		(fp_line
			(start -0.12065 -0.2794)
			(end -0.12065 -0.3048)
			(stroke
				(width 0.1)
				(type default)
			)
			(layer "B.Fab")
		)
		(fp_line
			(start -0.12065 -0.3048)
			(end -0.67945 -0.3048)
			(stroke
				(width 0.1)
				(type default)
			)
			(layer "B.Fab")
		)
		(fp_line
			(start -0.67945 0.3048)
			(end -0.120396 0.3048)
			(stroke
				(width 0.1)
				(type default)
			)
			(layer "B.Fab")
		)
		(fp_line
			(start -0.67945 -0.3048)
			(end -0.67945 0.3048)
			(stroke
				(width 0.1)
				(type default)
			)
			(layer "B.Fab")
		)
		(pad "1" smd circle
			(at 0.40005 0)
			(size 0 0)
			(layers "B.Cu" "B.Mask" "B.Paste")
			(net "XTAL_CPU0_X32K_X2")
		)
		(pad "2" smd circle
			(at -0.40005 0)
			(size 0 0)
			(layers "B.Cu" "B.Mask" "B.Paste")
			(net "GND")
		)
	)
	(footprint ""
		(layer "B.Cu")
		(at 239.980978 -315.95568 -90)
		(property "Reference" "PC6510"
			(at 0 0 90)
			(layer "B.SilkS")
			(hide yes)
			(effects
				(font
					(size 1.27 1.27)
				)
				(justify mirror)
			)
		)
		(property "Value" ""
			(at 0 0 90)
			(layer "B.Fab")
			(effects
				(font
					(size 1.27 1.27)
				)
				(justify mirror)
			)
		)
		(duplicate_pad_numbers_are_jumpers no)
		(fp_line
			(start -1.524 0.762)
			(end 1.524 0.762)
			(stroke
				(width 0.1524)
				(type default)
			)
			(layer "B.SilkS")
		)
		(fp_line
			(start 1.524 0.762)
			(end 1.524 -0.762)
			(stroke
				(width 0.1524)
				(type default)
			)
			(layer "B.SilkS")
		)
		(fp_line
			(start -1.524 -0.762)
			(end -1.524 0.762)
			(stroke
				(width 0.1524)
				(type default)
			)
			(layer "B.SilkS")
		)
		(fp_line
			(start 1.524 -0.762)
			(end -1.524 -0.762)
			(stroke
				(width 0.1524)
				(type default)
			)
			(layer "B.SilkS")
		)
		(fp_line
			(start -1.1049 0.724916)
			(end -1.1049 -0.724916)
			(stroke
				(width 0.1)
				(type default)
			)
			(layer "B.Fab")
		)
		(fp_line
			(start 1.1049 0.724916)
			(end -1.1049 0.724916)
			(stroke
				(width 0.1)
				(type default)
			)
			(layer "B.Fab")
		)
		(fp_line
			(start -1.1049 -0.724916)
			(end 1.1049 -0.724916)
			(stroke
				(width 0.1)
				(type default)
			)
			(layer "B.Fab")
		)
		(fp_line
			(start 1.1049 -0.724916)
			(end 1.1049 0.724916)
			(stroke
				(width 0.1)
				(type default)
			)
			(layer "B.Fab")
		)
		(pad "1" smd rect
			(at 0.889 0 270)
			(size 1.016 1.27)
			(layers "B.Cu" "B.Mask" "B.Paste")
			(net "P1V8_CPU0_RT_1D")
		)
		(pad "2" smd rect
			(at -0.889 0 270)
			(size 1.016 1.27)
			(layers "B.Cu" "B.Mask" "B.Paste")
			(net "GND")
		)
	)
	(footprint ""
		(layer "B.Cu")
		(at 105.960164 -260.305296 180)
		(property "Reference" "C2265"
			(at 0 0 0)
			(layer "B.SilkS")
			(hide yes)
			(effects
				(font
					(size 1.27 1.27)
				)
				(justify mirror)
			)
		)
		(property "Value" ""
			(at 0 0 0)
			(layer "B.Fab")
			(effects
				(font
					(size 1.27 1.27)
				)
				(justify mirror)
			)
		)
		(duplicate_pad_numbers_are_jumpers no)
		(fp_line
			(start 0.7874 0.4064)
			(end 0.7874 -0.4064)
			(stroke
				(width 0.1524)
				(type default)
			)
			(layer "B.SilkS")
		)
		(fp_line
			(start 0.7874 -0.4064)
			(end -0.7874 -0.4064)
			(stroke
				(width 0.1524)
				(type default)
			)
			(layer "B.SilkS")
		)
		(fp_line
			(start -0.7874 0.4064)
			(end 0.7874 0.4064)
			(stroke
				(width 0.1524)
				(type default)
			)
			(layer "B.SilkS")
		)
		(fp_line
			(start -0.7874 -0.4064)
			(end -0.7874 0.4064)
			(stroke
				(width 0.1524)
				(type default)
			)
			(layer "B.SilkS")
		)
		(fp_line
			(start 0.67945 0.3048)
			(end 0.67945 -0.305054)
			(stroke
				(width 0.1)
				(type default)
			)
			(layer "B.Fab")
		)
		(fp_line
			(start 0.67945 -0.305054)
			(end 0.12065 -0.305054)
			(stroke
				(width 0.1)
				(type default)
			)
			(layer "B.Fab")
		)
		(fp_line
			(start 0.12065 0.3048)
			(end 0.67945 0.3048)
			(stroke
				(width 0.1)
				(type default)
			)
			(layer "B.Fab")
		)
		(fp_line
			(start 0.12065 0.2794)
			(end 0.12065 0.3048)
			(stroke
				(width 0.1)
				(type default)
			)
			(layer "B.Fab")
		)
		(fp_line
			(start 0.12065 -0.2794)
			(end -0.12065 -0.2794)
			(stroke
				(width 0.1)
				(type default)
			)
			(layer "B.Fab")
		)
		(fp_line
			(start 0.12065 -0.305054)
			(end 0.12065 -0.2794)
			(stroke
				(width 0.1)
				(type default)
			)
			(layer "B.Fab")
		)
		(fp_line
			(start -0.120396 0.3048)
			(end -0.120396 0.2794)
			(stroke
				(width 0.1)
				(type default)
			)
			(layer "B.Fab")
		)
		(fp_line
			(start -0.120396 0.2794)
			(end 0.12065 0.2794)
			(stroke
				(width 0.1)
				(type default)
			)
			(layer "B.Fab")
		)
		(fp_line
			(start -0.12065 -0.2794)
			(end -0.12065 -0.3048)
			(stroke
				(width 0.1)
				(type default)
			)
			(layer "B.Fab")
		)
		(fp_line
			(start -0.12065 -0.3048)
			(end -0.67945 -0.3048)
			(stroke
				(width 0.1)
				(type default)
			)
			(layer "B.Fab")
		)
		(fp_line
			(start -0.67945 0.3048)
			(end -0.120396 0.3048)
			(stroke
				(width 0.1)
				(type default)
			)
			(layer "B.Fab")
		)
		(fp_line
			(start -0.67945 -0.3048)
			(end -0.67945 0.3048)
			(stroke
				(width 0.1)
				(type default)
			)
			(layer "B.Fab")
		)
		(pad "1" smd circle
			(at 0.40005 0)
			(size 0 0)
			(layers "B.Cu" "B.Mask" "B.Paste")
			(net "PVDDIO_P1")
		)
		(pad "2" smd circle
			(at -0.40005 0)
			(size 0 0)
			(layers "B.Cu" "B.Mask" "B.Paste")
			(net "GND")
		)
	)
)
